FILE_TYPE = CONNECTIVITY;
{Allegro Design Entry HDL 17.2-2016 S081 (4005846) 1/11/2022}
"PAGE_NUMBER" = 65;
0"NC";
END.
